0.01000 T01
0.02000 T02
0.02300 T03
0.02600 T04
0.02800 T05
0.04000 T06
0.08600 T07
0.16500 T08
